#ISCELL
  mstr_misc prelim *
  *
#ISCELL
  mstr_symbols design_note *
  *
#ISCELL
  mstr_symbols intel_corp_bpage *
  *
#ISCELL
  mstr_standard offpage *
  page34_i1
#ISCELL
  mstr_standard tap *
  page34_i10
#ISCELL
  mstr_standard tap *
  page34_i11
#ISCELL
  mstr_standard tap *
  page34_i12
#ISCELL
  mstr_standard tap *
  page34_i13
#ISCELL
  mstr_standard tap *
  page34_i14
#ISCELL
  mstr_standard tap *
  page34_i15
#ISCELL
  mstr_standard tap *
  page34_i16
#ISCELL
  mstr_standard tap *
  page34_i17
#ISCELL
  mstr_standard tap *
  page34_i18
#ISCELL
  mstr_standard tap *
  page34_i19
#ISCELL
  mstr_standard offpage *
  page34_i2
#ISCELL
  mstr_standard tap *
  page34_i20
#ISCELL
  mstr_standard tap *
  page34_i21
#ISCELL
  mstr_standard tap *
  page34_i22
#ISCELL
  mstr_standard tap *
  page34_i23
#ISCELL
  mstr_standard tap *
  page34_i24
#ISCELL
  mstr_standard tap *
  page34_i25
#ISCELL
  mstr_standard tap *
  page34_i26
#ISCELL
  mstr_standard tap *
  page34_i27
#ISCELL
  mstr_standard tap *
  page34_i28
#ISCELL
  mstr_standard tap *
  page34_i29
#ISCELL
  mstr_standard tap *
  page34_i3
#ISCELL
  mstr_standard tap *
  page34_i30
#ISCELL
  mstr_standard tap *
  page34_i31
#ISCELL
  mstr_standard tap *
  page34_i32
#ISCELL
  mstr_standard tap *
  page34_i33
#ISCELL
  mstr_standard tap *
  page34_i34
#ISCELL
  mstr_standard tap *
  page34_i35
#ISCELL
  mstr_standard tap *
  page34_i36
#ISCELL
  mstr_standard tap *
  page34_i37
#ISCELL
  mstr_standard tap *
  page34_i38
#ISCELL
  mstr_standard tap *
  page34_i39
#ISCELL
  mstr_standard tap *
  page34_i4
#ISCELL
  mstr_standard tap *
  page34_i40
#ISCELL
  mstr_standard tap *
  page34_i41
#ISCELL
  mstr_standard tap *
  page34_i42
#ISCELL
  mstr_standard tap *
  page34_i43
#ISCELL
  mstr_standard tap *
  page34_i44
#ISCELL
  mstr_standard tap *
  page34_i45
#ISCELL
  mstr_standard tap *
  page34_i46
#ISCELL
  mstr_standard tap *
  page34_i47
#ISCELL
  mstr_standard tap *
  page34_i48
#ISCELL
  mstr_standard tap *
  page34_i49
#ISCELL
  mstr_standard tap *
  page34_i5
#ISCELL
  mstr_standard tap *
  page34_i50
#ISCELL
  mstr_standard tap *
  page34_i51
#ISCELL
  mstr_standard tap *
  page34_i52
#ISCELL
  mstr_standard tap *
  page34_i53
#ISCELL
  mstr_standard tap *
  page34_i54
#ISCELL
  mstr_standard tap *
  page34_i55
#ISCELL
  mstr_standard tap *
  page34_i56
#ISCELL
  mstr_standard tap *
  page34_i57
#ISCELL
  mstr_standard tap *
  page34_i58
#ISCELL
  mstr_standard tap *
  page34_i59
#ISCELL
  mstr_standard tap *
  page34_i6
#ISCELL
  mstr_standard tap *
  page34_i60
#ISCELL
  mstr_standard tap *
  page34_i61
#ISCELL
  mstr_standard tap *
  page34_i62
#ISCELL
  mstr_standard tap *
  page34_i63
#ISCELL
  mstr_standard tap *
  page34_i64
#ISCELL
  mstr_standard tap *
  page34_i65
#ISCELL
  mstr_standard tap *
  page34_i66
#ISCELL
  mstr_standard tap *
  page34_i67
#ISCELL
  mstr_standard tap *
  page34_i68
#ISCELL
  mstr_standard tap *
  page34_i69
#ISCELL
  mstr_standard tap *
  page34_i7
#ISCELL
  mstr_standard tap *
  page34_i70
#ISCELL
  mstr_standard tap *
  page34_i71
#ISCELL
  mstr_standard tap *
  page34_i72
#ISCELL
  mstr_standard tap *
  page34_i73
#ISCELL
  mstr_standard tap *
  page34_i74
#ISCELL
  mstr_standard tap *
  page34_i75
#ISCELL
  mstr_standard tap *
  page34_i76
#ISCELL
  mstr_standard tap *
  page34_i77
#ISCELL
  mstr_standard tap *
  page34_i78
#ISCELL
  mstr_standard tap *
  page34_i79
#ISCELL
  mstr_standard tap *
  page34_i80
#ISCELL
  mstr_standard tap *
  page34_i81
#ISCELL
  mstr_standard tap *
  page34_i82
#ISCELL
  mstr_standard tap *
  page34_i83
#ISCELL
  mstr_standard offpage *
  page34_i84
#ISCELL
  mstr_standard offpage *
  page34_i85
#CELL
  chpset_lib skx_ext_b *
  page34_i86
#ISCELL
  mstr_standard tap *
  page34_i9
